# S9S_MB_2U (Grand Teton) — schematic netlist excerpt (pin names and nets, part order shuffled) for the footprints in the layout excerpt that follows; sources: Cadence DE-HDL packaged netlist, KiCad conversion of 03242023_DA0F0TMBIJ0_F0T_Motherboard_J_brd_V01_OCP.brd

J2  SCONN288_ADR50017P087CC  SCONN288_ADR50017-P087CC IO  pkg DDR288S_1-1VXB  page 83
  VIN_BULK0  = P12V_S3_AUX_CPU0_NVDIMM
  RFU0  = TP_CHA_CPU0_DIMM2_FRU_0
  VIN_MGMT  = P3V3_AUX
  HSCL  = I3C_SPD_DDRABCD_CPU0_LVC1_SCL_1
  HSDA  = I3C_SPD_DDRABCD_CPU0_LVC1_SDA
  VSS0  = GND
  DQ0_A  = M_A_CPU0_SA_DQ<0>
  VSS1  = GND
  DQ1_A  = M_A_CPU0_SA_DQ<1>
  VSS2  = GND
  DQS0_A_T  = M_A_CPU0_SA_DQS_DP<0>
  DQS0_A_C  = M_A_CPU0_SA_DQS_DN<0>
  VSS3  = GND
  DQ4_A  = M_A_CPU0_SA_DQ<4>
  VSS4  = GND
  DQ5_A  = M_A_CPU0_SA_DQ<5>
  VSS5  = GND
  DQ8_A  = M_A_CPU0_SA_DQ<8>
  VSS6  = GND
  DQ9_A  = M_A_CPU0_SA_DQ<9>
  VSS7  = GND
  DQS1_A_T  = M_A_CPU0_SA_DQS_DP<1>
  DQS1_A_C  = M_A_CPU0_SA_DQS_DN<1>
  VSS8  = GND
  DQ12_A  = M_A_CPU0_SA_DQ<12>
  VSS9  = GND
  DQ13_A  = M_A_CPU0_SA_DQ<13>
  VSS10  = GND
  DQ16_A  = M_A_CPU0_SA_DQ<16>
  VSS11  = GND
  DQ17_A  = M_A_CPU0_SA_DQ<17>
  VSS12  = GND
  DQS2_A_T  = M_A_CPU0_SA_DQS_DP<2>
  DQS2_A_C  = M_A_CPU0_SA_DQS_DN<2>
  VSS13  = GND
  DQ20_A  = M_A_CPU0_SA_DQ<20>
  VSS14  = GND
  DQ21_A  = M_A_CPU0_SA_DQ<21>
  VSS15  = GND
  DQ24_A  = M_A_CPU0_SA_DQ<24>
  VSS16  = GND
  DQ25_A  = M_A_CPU0_SA_DQ<25>
  VSS17  = GND
  DQS3_A_T  = M_A_CPU0_SA_DQS_DP<3>
  DQS3_A_C  = M_A_CPU0_SA_DQS_DN<3>
  VSS18  = GND
  DQ28_A  = M_A_CPU0_SA_DQ<28>
  VSS19  = GND
  DQ29_A  = M_A_CPU0_SA_DQ<29>
  VSS20  = GND
  CB0_A  = M_A_CPU0_SA_CB<0>
  VSS21  = GND
  CB1_A  = M_A_CPU0_SA_CB<1>
  VSS22  = GND
  DQS4_A_T  = M_A_CPU0_SA_DQS_DP<4>
  DQS4_A_C  = M_A_CPU0_SA_DQS_DN<4>
  VSS23  = GND
  CB4_A  = M_A_CPU0_SA_CB<4>
  VSS24  = GND
  CB5_A  = M_A_CPU0_SA_CB<5>
  VSS25  = GND
  ALERT_N  = M_A_CPU0_ALERT_N
  VSS26  = GND
  CS0_A_N  = M_A_CPU0_SA_CS_N<2>
  VSS27  = GND
  CA0_A  = M_A_CPU0_SA_CA<0>
  VSS28  = GND
  CA2_A  = M_A_CPU0_SA_CA<2>
  VSS29  = GND
  CA4_A  = M_A_CPU0_SA_CA<4>
  VSS30  = GND
  CA6_A  = M_A_CPU0_SA_CA<6>
  VSS31  = GND
  PAR_A  = M_A_CPU0_SA_PAR
  VSS32  = GND
  CA0_B  = M_A_CPU0_SB_CA<0>
  VSS33  = GND
  CA2_B  = M_A_CPU0_SB_CA<2>
  VSS34  = GND
  CA4_B  = M_A_CPU0_SB_CA<4>
  VSS35  = GND
  CA6_B  = M_A_CPU0_SB_CA<6>
  VSS36  = GND
  CS0_B_N  = M_A_CPU0_SB_CS_N<2>
  VSS37  = GND
  \lbd||rsp_a_n\  = M_A_CPU0_SA_RSP<1>
  \lbs||rsp_b_n\  = M_A_CPU0_SB_RSP<1>
  VSS38  = GND
  CB4_B  = M_A_CPU0_SB_CB<4>
  VSS39  = GND
  CB5_B  = M_A_CPU0_SB_CB<5>
  VSS40  = GND
  \dqs9_b_t||tdqs9_b_t||dbi4_b_n\  = M_A_CPU0_SB_DQS_DP<9>
  \dqs9_b_c||tdqs9_b_c\  = M_A_CPU0_SB_DQS_DN<9>
  VSS41  = GND
  CB0_B  = M_A_CPU0_SB_CB<0>
  VSS42  = GND
  CB1_B  = M_A_CPU0_SB_CB<1>
  VSS43  = GND
  DQ0_B  = M_A_CPU0_SB_DQ<0>
  VSS44  = GND
  DQ1_B  = M_A_CPU0_SB_DQ<1>
  VSS45  = GND
  DQS0_B_T  = M_A_CPU0_SB_DQS_DP<0>
  DQS0_B_C  = M_A_CPU0_SB_DQS_DN<0>
  VSS46  = GND
  DQ4_B  = M_A_CPU0_SB_DQ<4>
  VSS47  = GND
  DQ5_B  = M_A_CPU0_SB_DQ<5>
  VSS48  = GND
  DQ8_B  = M_A_CPU0_SB_DQ<8>
  VSS49  = GND
  DQ9_B  = M_A_CPU0_SB_DQ<9>
  VSS50  = GND
  DQS1_B_T  = M_A_CPU0_SB_DQS_DP<1>
  DQS1_B_C  = M_A_CPU0_SB_DQS_DN<1>
  VSS51  = GND
  DQ12_B  = M_A_CPU0_SB_DQ<12>
  VSS52  = GND
  DQ13_B  = M_A_CPU0_SB_DQ<13>
  VSS53  = GND
  DQ16_B  = M_A_CPU0_SB_DQ<16>
  VSS54  = GND
  DQ17_B  = M_A_CPU0_SB_DQ<17>
  VSS55  = GND
  DQS2_B_T  = M_A_CPU0_SB_DQS_DP<2>
  DQS2_B_C  = M_A_CPU0_SB_DQS_DN<2>
  VSS56  = GND
  DQ20_B  = M_A_CPU0_SB_DQ<20>
  VSS57  = GND
  DQ21_B  = M_A_CPU0_SB_DQ<21>
  VSS58  = GND
  DQ24_B  = M_A_CPU0_SB_DQ<24>
  VSS59  = GND
  DQ25_B  = M_A_CPU0_SB_DQ<25>
  VSS60  = GND
  DQS3_B_T  = M_A_CPU0_SB_DQS_DP<3>
  DQS3_B_C  = M_A_CPU0_SB_DQS_DN<3>
  VSS61  = GND
  DQ28_B  = M_A_CPU0_SB_DQ<28>
  VSS62  = GND
  DQ29_B  = M_A_CPU0_SB_DQ<29>
  VSS63  = GND
  RFU1  = TP_CHA_CPU0_DIMM2_FRU_1
  VIN_BULK1  = P12V_S3_AUX_CPU0_NVDIMM
  VIN_BULK2  = P12V_S3_AUX_CPU0_NVDIMM
  \pwr_good||fail_n\  = PWRGD_CHA_CPU0_DIMM2
  HSA  = PD_CHA_CPU0_DIMM2_SAA
  RFU2  = TP_CHA_CPU0_DIMM2_FRU_2
  RFU3  = TP_CHA_CPU0_DIMM2_FRU_3
  VSS64  = GND
  DQ2_A  = M_A_CPU0_SA_DQ<2>
  VSS65  = GND
  DQ3_A  = M_A_CPU0_SA_DQ<3>
  VSS66  = GND
  \dqs5_a_c||tdqs5_a_c||dqs5_a_t||tdqs5_a_t\  = M_A_CPU0_SA_DQS_DN<5>
  \dqs5_a_t||tdqs5_a_t\  = M_A_CPU0_SA_DQS_DP<5>
  VSS67  = GND
  DQ6_A  = M_A_CPU0_SA_DQ<6>
  VSS68  = GND
  DQ7_A  = M_A_CPU0_SA_DQ<7>
  VSS69  = GND
  DQ10_A  = M_A_CPU0_SA_DQ<10>
  VSS70  = GND
  DQ11_A  = M_A_CPU0_SA_DQ<11>
  VSS71  = GND
  \dqs6_a_c||tdqs6_a_c||dqs6_a_t||tdqs6_a_t\  = M_A_CPU0_SA_DQS_DN<6>
  \dqs6_a_t||tdqs6_a_t\  = M_A_CPU0_SA_DQS_DP<6>
  VSS72  = GND
  DQ14_A  = M_A_CPU0_SA_DQ<14>
  VSS73  = GND
  DQ15_A  = M_A_CPU0_SA_DQ<15>
  VSS74  = GND
  DQ18_A  = M_A_CPU0_SA_DQ<18>
  VSS75  = GND
  DQ19_A  = M_A_CPU0_SA_DQ<19>
  VSS76  = GND
  \dqs7_a_c||tdqs7_a_c\  = M_A_CPU0_SA_DQS_DN<7>
  \dqs7_a_t||tdqs7_a_t\  = M_A_CPU0_SA_DQS_DP<7>
  VSS77  = GND
  DQ22_A  = M_A_CPU0_SA_DQ<22>
  VSS78  = GND
  DQ23_A  = M_A_CPU0_SA_DQ<23>
  VSS79  = GND
  DQ26_A  = M_A_CPU0_SA_DQ<26>
  VSS80  = GND
  DQ27_A  = M_A_CPU0_SA_DQ<27>
  VSS81  = GND
  \dqs8_a_c||tdqs8_a_c\  = M_A_CPU0_SA_DQS_DN<8>
  \dqs8_a_t||tdqs8_a_t\  = M_A_CPU0_SA_DQS_DP<8>
  VSS82  = GND
  DQ30_A  = M_A_CPU0_SA_DQ<30>
  VSS83  = GND
  DQ31_A  = M_A_CPU0_SA_DQ<31>
  VSS84  = GND
  CB2_A  = M_A_CPU0_SA_CB<2>
  VSS85  = GND
  CB3_A  = M_A_CPU0_SA_CB<3>
  VSS86  = GND
  \dqs9_a_c||tdqs9_a_c\  = M_A_CPU0_SA_DQS_DN<9>
  \dqs9_a_t||tdqs9_a_t\  = M_A_CPU0_SA_DQS_DP<9>
  VSS87  = GND
  CB6_A  = M_A_CPU0_SA_CB<6>
  VSS88  = GND
  CB7_A  = M_A_CPU0_SA_CB<7>
  VSS89  = GND
  RESET_N  = RST_M_AB_CPU0_FPGA_N
  VSS90  = GND
  CS1_A_N  = M_A_CPU0_SA_CS_N<3>
  VSS91  = GND
  CA1_A  = M_A_CPU0_SA_CA<1>
  VSS92  = GND
  CA3_A  = M_A_CPU0_SA_CA<3>
  VSS93  = GND
  CA5_A  = M_A_CPU0_SA_CA<5>
  VSS94  = GND
  CK_T  = M_A_CPU0_CLK_DP<1>
  CK_C  = M_A_CPU0_CLK_DN<1>
  VSS95  = GND
  RFU4  = TP_CHA_CPU0_DIMM2_FRU_4
  CA1_B  = M_A_CPU0_SB_CA<1>
  VSS96  = GND
  CA3_B  = M_A_CPU0_SB_CA<3>
  VSS97  = GND
  CA5_B  = M_A_CPU0_SB_CA<5>
  VSS98  = GND
  PAR_B  = M_A_CPU0_SB_PAR
  VSS99  = GND
  CS1_B_N  = M_A_CPU0_SB_CS_N<3>
  VSS100  = GND
  RFU5  = TP_CHA_CPU0_DIMM2_FRU_5
  RFU6  = TP_CHA_CPU0_DIMM2_FRU_6
  VSS101  = GND
  CB6_B  = M_A_CPU0_SB_CB<6>
  VSS102  = GND
  CB7_B  = M_A_CPU0_SB_CB<7>
  VSS103  = GND
  DQS4_B_C  = M_A_CPU0_SB_DQS_DN<4>
  DQS4_B_T  = M_A_CPU0_SB_DQS_DP<4>
  VSS104  = GND
  CB2_B  = M_A_CPU0_SB_CB<2>
  VSS105  = GND
  CB3_B  = M_A_CPU0_SB_CB<3>
  VSS106  = GND
  DQ2_B  = M_A_CPU0_SB_DQ<2>
  VSS107  = GND
  DQ3_B  = M_A_CPU0_SB_DQ<3>
  VSS108  = GND
  \dqs5_b_c||tdqs5_b_c\  = M_A_CPU0_SB_DQS_DN<5>
  \dqs5_b_t||tdqs5_b_t\  = M_A_CPU0_SB_DQS_DP<5>
  VSS109  = GND
  DQ6_B  = M_A_CPU0_SB_DQ<6>
  VSS110  = GND
  DQ7_B  = M_A_CPU0_SB_DQ<7>
  VSS111  = GND
  DQ10_B  = M_A_CPU0_SB_DQ<10>
  VSS112  = GND
  DQ11_B  = M_A_CPU0_SB_DQ<11>
  VSS113  = GND
  \dqs6_b_c||tdqs6_b_c\  = M_A_CPU0_SB_DQS_DN<6>
  \dqs6_b_t||tdqs6_b_t\  = M_A_CPU0_SB_DQS_DP<6>
  VSS114  = GND
  DQ14_B  = M_A_CPU0_SB_DQ<14>
  VSS115  = GND
  DQ15_B  = M_A_CPU0_SB_DQ<15>
  VSS116  = GND
  DQ18_B  = M_A_CPU0_SB_DQ<18>
  VSS117  = GND
  DQ19_B  = M_A_CPU0_SB_DQ<19>
  VSS118  = GND
  \dqs7_b_c||tdqs7_b_c\  = M_A_CPU0_SB_DQS_DN<7>
  \dqs7_b_t||tdqs7_b_t\  = M_A_CPU0_SB_DQS_DP<7>
  VSS119  = GND
  DQ22_B  = M_A_CPU0_SB_DQ<22>
  VSS120  = GND
  DQ23_B  = M_A_CPU0_SB_DQ<23>
  VSS121  = GND
  DQ26_B  = M_A_CPU0_SB_DQ<26>
  VSS122  = GND
  DQ27_B  = M_A_CPU0_SB_DQ<27>
  VSS123  = GND
  \dqs8_b_c||tdqs8_b_c\  = M_A_CPU0_SB_DQS_DN<8>
  \dqs8_b_t||tdqs8_b_t\  = M_A_CPU0_SB_DQS_DP<8>
  VSS124  = GND
  DQ30_B  = M_A_CPU0_SB_DQ<30>
  VSS125  = GND
  DQ31_B  = M_A_CPU0_SB_DQ<31>
  VSS126  = GND
  G1  = GND
  G2  = GND
  G3  = GND

(kicad_pcb
	(version 20260206)
	(generator "pcbnew")
	(generator_version "10.0")
	(general
		(thickness 1.6)
		(legacy_teardrops no)
	)
	(paper "A4")
	(title_block
		(title "03242023_DA0F0TMBIJ0_F0T_Motherboard_J_brd_V01_OCP.brd")
		(comment 1 "Grand Teton / footprint 2856 of 6105 (J2), pads 229-274 of 291")
	)
	(layers
		(0 "F.Cu" signal "TOP")
		(4 "In1.Cu" signal "GND")
		(6 "In2.Cu" signal "IN1")
		(8 "In3.Cu" signal "GND1")
		(10 "In4.Cu" signal "IN2")
		(12 "In5.Cu" signal "GND2")
		(14 "In6.Cu" signal "IN3")
		(16 "In7.Cu" signal "GND3")
		(18 "In8.Cu" signal "VCC")
		(20 "In9.Cu" signal "VCC1")
		(22 "In10.Cu" signal "GND4")
		(24 "In11.Cu" signal "IN4")
		(26 "In12.Cu" signal "GND5")
		(28 "In13.Cu" signal "IN5")
		(30 "In14.Cu" signal "GND6")
		(32 "In15.Cu" signal "IN6")
		(34 "In16.Cu" signal "GND7")
		(2 "B.Cu" signal "BOTTOM")
		(9 "F.Adhes" user "F.Adhesive")
		(11 "B.Adhes" user "B.Adhesive")
		(13 "F.Paste" user "Package Geometry/Pastemask Top")
		(15 "B.Paste" user "Package Geometry/Pastemask Bottom")
		(5 "F.SilkS" user "Ref Des/Silkscreen Top")
		(7 "B.SilkS" user "Ref Des/Silkscreen Bottom")
		(1 "F.Mask" user "Board Geometry/Soldermask Top")
		(3 "B.Mask" user "Board Geometry/Soldermask Bottom")
		(17 "Dwgs.User" user "User.Drawings")
		(19 "Cmts.User" user "User.Comments")
		(21 "Eco1.User" user "User.Eco1")
		(23 "Eco2.User" user "User.Eco2")
		(25 "Edge.Cuts" user "Board Geometry/Outline")
		(27 "Margin" user)
		(31 "F.CrtYd" user "Package Geometry/Place Bound Top")
		(29 "B.CrtYd" user "Package Geometry/Place Bound Bottom")
		(35 "F.Fab" user "Ref Des/Assembly Top")
		(33 "B.Fab" user "Ref Des/Assembly Bottom")
	)
	(footprint ""
		(layer "F.Cu")
		(at 310.937148 -258.091686)
		(property "Reference" "J2"
			(at -3.683 -81.702148 0)
			(unlocked yes)
			(layer "F.SilkS")
			(effects
				(font
					(size 0.7874 0.5842)
					(thickness 0.1524)
				)
				(justify left)
			)
		)
		(property "Value" ""
			(at 0 0 0)
			(layer "F.Fab")
			(effects
				(font
					(size 1.27 1.27)
				)
			)
		)
		(duplicate_pad_numbers_are_jumpers no)
		(pad "229" smd rect
			(at 2.050034 13.17498 270)
			(size 0.519938 1.4986)
			(layers "F.Cu" "F.Mask" "F.Paste")
			(net "M_A_CPU0_SB_CS_N<3>")
		)
		(pad "230" smd rect
			(at 2.050034 14.025118 270)
			(size 0.519938 1.4986)
			(layers "F.Cu" "F.Mask" "F.Paste")
			(net "GND")
		)
		(pad "231" smd rect
			(at 2.050034 14.875002 270)
			(size 0.519938 1.4986)
			(layers "F.Cu" "F.Mask" "F.Paste")
			(net "TP_CHA_CPU0_DIMM2_FRU_5")
		)
		(pad "232" smd rect
			(at 2.050034 15.724886 270)
			(size 0.519938 1.4986)
			(layers "F.Cu" "F.Mask" "F.Paste")
			(net "TP_CHA_CPU0_DIMM2_FRU_6")
		)
		(pad "233" smd rect
			(at 2.050034 16.575024 270)
			(size 0.519938 1.4986)
			(layers "F.Cu" "F.Mask" "F.Paste")
			(net "GND")
		)
		(pad "234" smd rect
			(at 2.050034 17.424908 270)
			(size 0.519938 1.4986)
			(layers "F.Cu" "F.Mask" "F.Paste")
			(net "M_A_CPU0_SB_CB<6>")
		)
		(pad "235" smd rect
			(at 2.050034 18.275046 270)
			(size 0.519938 1.4986)
			(layers "F.Cu" "F.Mask" "F.Paste")
			(net "GND")
		)
		(pad "236" smd rect
			(at 2.050034 19.12493 270)
			(size 0.519938 1.4986)
			(layers "F.Cu" "F.Mask" "F.Paste")
			(net "M_A_CPU0_SB_CB<7>")
		)
		(pad "237" smd rect
			(at 2.050034 19.975068 270)
			(size 0.519938 1.4986)
			(layers "F.Cu" "F.Mask" "F.Paste")
			(net "GND")
		)
		(pad "238" smd rect
			(at 2.050034 20.824952 270)
			(size 0.519938 1.4986)
			(layers "F.Cu" "F.Mask" "F.Paste")
			(net "M_A_CPU0_SB_DQS_DN<4>")
		)
		(pad "239" smd rect
			(at 2.050034 21.67509 270)
			(size 0.519938 1.4986)
			(layers "F.Cu" "F.Mask" "F.Paste")
			(net "M_A_CPU0_SB_DQS_DP<4>")
		)
		(pad "240" smd rect
			(at 2.050034 22.524974 270)
			(size 0.519938 1.4986)
			(layers "F.Cu" "F.Mask" "F.Paste")
			(net "GND")
		)
		(pad "241" smd rect
			(at 2.050034 23.375112 270)
			(size 0.519938 1.4986)
			(layers "F.Cu" "F.Mask" "F.Paste")
			(net "M_A_CPU0_SB_CB<2>")
		)
		(pad "242" smd rect
			(at 2.050034 24.224996 270)
			(size 0.519938 1.4986)
			(layers "F.Cu" "F.Mask" "F.Paste")
			(net "GND")
		)
		(pad "243" smd rect
			(at 2.050034 25.07488 270)
			(size 0.519938 1.4986)
			(layers "F.Cu" "F.Mask" "F.Paste")
			(net "M_A_CPU0_SB_CB<3>")
		)
		(pad "244" smd rect
			(at 2.050034 25.925018 270)
			(size 0.519938 1.4986)
			(layers "F.Cu" "F.Mask" "F.Paste")
			(net "GND")
		)
		(pad "245" smd rect
			(at 2.050034 26.774902 270)
			(size 0.519938 1.4986)
			(layers "F.Cu" "F.Mask" "F.Paste")
			(net "M_A_CPU0_SB_DQ<2>")
		)
		(pad "246" smd rect
			(at 2.050034 27.62504 270)
			(size 0.519938 1.4986)
			(layers "F.Cu" "F.Mask" "F.Paste")
			(net "GND")
		)
		(pad "247" smd rect
			(at 2.050034 28.474924 270)
			(size 0.519938 1.4986)
			(layers "F.Cu" "F.Mask" "F.Paste")
			(net "M_A_CPU0_SB_DQ<3>")
		)
		(pad "248" smd rect
			(at 2.050034 29.325062 270)
			(size 0.519938 1.4986)
			(layers "F.Cu" "F.Mask" "F.Paste")
			(net "GND")
		)
		(pad "249" smd rect
			(at 2.050034 30.174946 270)
			(size 0.519938 1.4986)
			(layers "F.Cu" "F.Mask" "F.Paste")
			(net "M_A_CPU0_SB_DQS_DN<5>")
		)
		(pad "250" smd rect
			(at 2.050034 31.025084 270)
			(size 0.519938 1.4986)
			(layers "F.Cu" "F.Mask" "F.Paste")
			(net "M_A_CPU0_SB_DQS_DP<5>")
		)
		(pad "251" smd rect
			(at 2.050034 31.874968 270)
			(size 0.519938 1.4986)
			(layers "F.Cu" "F.Mask" "F.Paste")
			(net "GND")
		)
		(pad "252" smd rect
			(at 2.050034 32.725106 270)
			(size 0.519938 1.4986)
			(layers "F.Cu" "F.Mask" "F.Paste")
			(net "M_A_CPU0_SB_DQ<6>")
		)
		(pad "253" smd rect
			(at 2.050034 33.57499 270)
			(size 0.519938 1.4986)
			(layers "F.Cu" "F.Mask" "F.Paste")
			(net "GND")
		)
		(pad "254" smd rect
			(at 2.050034 34.425128 270)
			(size 0.519938 1.4986)
			(layers "F.Cu" "F.Mask" "F.Paste")
			(net "M_A_CPU0_SB_DQ<7>")
		)
		(pad "255" smd rect
			(at 2.050034 35.275012 270)
			(size 0.519938 1.4986)
			(layers "F.Cu" "F.Mask" "F.Paste")
			(net "GND")
		)
		(pad "256" smd rect
			(at 2.050034 36.124896 270)
			(size 0.519938 1.4986)
			(layers "F.Cu" "F.Mask" "F.Paste")
			(net "M_A_CPU0_SB_DQ<10>")
		)
		(pad "257" smd rect
			(at 2.050034 36.975034 270)
			(size 0.519938 1.4986)
			(layers "F.Cu" "F.Mask" "F.Paste")
			(net "GND")
		)
		(pad "258" smd rect
			(at 2.050034 37.824918 270)
			(size 0.519938 1.4986)
			(layers "F.Cu" "F.Mask" "F.Paste")
			(net "M_A_CPU0_SB_DQ<11>")
		)
		(pad "259" smd rect
			(at 2.050034 38.675056 270)
			(size 0.519938 1.4986)
			(layers "F.Cu" "F.Mask" "F.Paste")
			(net "GND")
		)
		(pad "260" smd rect
			(at 2.050034 39.52494 270)
			(size 0.519938 1.4986)
			(layers "F.Cu" "F.Mask" "F.Paste")
			(net "M_A_CPU0_SB_DQS_DN<6>")
		)
		(pad "261" smd rect
			(at 2.050034 40.375078 270)
			(size 0.519938 1.4986)
			(layers "F.Cu" "F.Mask" "F.Paste")
			(net "M_A_CPU0_SB_DQS_DP<6>")
		)
		(pad "262" smd rect
			(at 2.050034 41.224962 270)
			(size 0.519938 1.4986)
			(layers "F.Cu" "F.Mask" "F.Paste")
			(net "GND")
		)
		(pad "263" smd rect
			(at 2.050034 42.0751 270)
			(size 0.519938 1.4986)
			(layers "F.Cu" "F.Mask" "F.Paste")
			(net "M_A_CPU0_SB_DQ<14>")
		)
		(pad "264" smd rect
			(at 2.050034 42.924984 270)
			(size 0.519938 1.4986)
			(layers "F.Cu" "F.Mask" "F.Paste")
			(net "GND")
		)
		(pad "265" smd rect
			(at 2.050034 43.775122 270)
			(size 0.519938 1.4986)
			(layers "F.Cu" "F.Mask" "F.Paste")
			(net "M_A_CPU0_SB_DQ<15>")
		)
		(pad "266" smd rect
			(at 2.050034 44.625006 270)
			(size 0.519938 1.4986)
			(layers "F.Cu" "F.Mask" "F.Paste")
			(net "GND")
		)
		(pad "267" smd rect
			(at 2.050034 45.47489 270)
			(size 0.519938 1.4986)
			(layers "F.Cu" "F.Mask" "F.Paste")
			(net "M_A_CPU0_SB_DQ<18>")
		)
		(pad "268" smd rect
			(at 2.050034 46.325028 270)
			(size 0.519938 1.4986)
			(layers "F.Cu" "F.Mask" "F.Paste")
			(net "GND")
		)
		(pad "269" smd rect
			(at 2.050034 47.174912 270)
			(size 0.519938 1.4986)
			(layers "F.Cu" "F.Mask" "F.Paste")
			(net "M_A_CPU0_SB_DQ<19>")
		)
		(pad "270" smd rect
			(at 2.050034 48.02505 270)
			(size 0.519938 1.4986)
			(layers "F.Cu" "F.Mask" "F.Paste")
			(net "GND")
		)
		(pad "271" smd rect
			(at 2.050034 48.874934 270)
			(size 0.519938 1.4986)
			(layers "F.Cu" "F.Mask" "F.Paste")
			(net "M_A_CPU0_SB_DQS_DN<7>")
		)
		(pad "272" smd rect
			(at 2.050034 49.725072 270)
			(size 0.519938 1.4986)
			(layers "F.Cu" "F.Mask" "F.Paste")
			(net "M_A_CPU0_SB_DQS_DP<7>")
		)
		(pad "273" smd rect
			(at 2.050034 50.574956 270)
			(size 0.519938 1.4986)
			(layers "F.Cu" "F.Mask" "F.Paste")
			(net "GND")
		)
		(pad "274" smd rect
			(at 2.050034 51.425094 270)
			(size 0.519938 1.4986)
			(layers "F.Cu" "F.Mask" "F.Paste")
			(net "M_A_CPU0_SB_DQ<22>")
		)
	)
)
